FILE_TYPE = MACRO_DRAWING;
SET COLOR_WIRE YELLOW;
SET COLOR_PROP ORANGE;
SET COLOR_DOT WHITE;
SET COLOR_ARC YELLOW;
SET COLOR_BODY GREEN;
SET COLOR_NOTE PURPLE;
SET PROP_DISPLAY VALUE;
SET PAGE_NUMBER P135;
FORCEADD QUANTA_TITLE_BLOCK_C..1
(-100 100);
FORCEPROP 1 LAST CUSTOM_TXT_CDS <NAME_2>
J 0
(-3275 150);
FORCEPROP 1 LAST CUSTOM_TXT_CDS <NAME_1>
J 0
(-3275 275);
FORCEPROP 1 LAST CUSTOM_TXT_CDS <Q_NUMBER>
J 0
(-1503 203);
DISPLAY 1.212766 (-1503 203);
FORCEPROP 1 LAST CUSTOM_TXT_CDS <Q_PROJ>
J 0
(-2482 202);
DISPLAY 1.212766 (-2482 202);
FORCEPROP 1 LAST CUSTOM_TXT_CDS <Q_REV>
J 0
(-284 203);
DISPLAY 1.212766 (-284 203);
FORCEPROP 1 LAST CUSTOM_TXT_CDS <CON_LAST_MODIFIED>
J 0
(-1985 115);
DISPLAY 0.978723 (-1985 115);
FORCEPROP 1 LAST CUSTOM_TXT_CDS <CON_PAGE_NUM> OF <CON_TOTAL_PAGES>
J 0
(-546 118);
DISPLAY 0.978723 (-546 118);
FORCEPROP 1 LAST Q_TITLE BOARD ID/FRU EEPROM
J 0
(-9350 175);
DISPLAY 2.446809 (-9350 175);
PAINT GREEN (-9350 175);
FORCEPROP 1 LAST Q_DEPT BU9
J 1
(-3863 149);
DISPLAY 1.957447 (-3863 149);
PAINT GREEN (-3863 149);
FORCEPROP 2 LAST PAGE_BORDER TRUE
J 0
(-7990 5350);
DISPLAY 0.638298 (-7990 5350);
PAINT PINK (-7990 5350);
DISPLAY INVISIBLE (-7990 5350);
FORCEPROP 1 LAST CDS_LMAN_SYM_OUTLINE -9475,6775,100,-125
J 0
(-100 100);
DISPLAY 0.468085 (-100 100);
PAINT GREEN (-100 100);
DISPLAY INVISIBLE (-100 100);
FORCEPROP 2 LAST CDS_LIB pure_quanta
J 0
(-100 100);
DISPLAY INVISIBLE (-100 100);
FORCEPROP 1 LAST COMMENT_BODY TRUE
J 0
(-88 87);
DISPLAY 0.978723 (-88 87);
PAINT GREEN (-88 87);
DISPLAY INVISIBLE (-88 87);
FORCEPROP 2 LAST CDS_XR_PAGE_TITLE CR-135 : @T6G_MB_LIB.T6G(SCH_1):PAGE135
J 0
(-7990 5350);
DISPLAY 0.638298 (-7990 5350);
PAINT PINK (-7990 5350);
DISPLAY INVISIBLE (-7990 5350);
FORCEPROP 2 LAST CUSTOM_TXT_CDS <XR_PAGE_TITLE>
J 0
(-7990 5350);
DISPLAY 0.638298 (-7990 5350);
PAINT PINK (-7990 5350);
DISPLAY INVISIBLE (-7990 5350);
FORCEPROP 0 LAST CDS_CON_LAST_MODIFIED Wed Mar 09 18:58:02 2022
J 0
(-1985 115);
DISPLAY INVISIBLE (-1985 115);
QUIT
